(kicad_pcb
	(version 20260206)
	(generator "pcbnew")
	(generator_version "10.0")
	(general
		(thickness 1.6)
		(legacy_teardrops no)
	)
	(paper "A4")
	(title_block
		(title "fcb — Lightning_FCB_BRD.brd")
		(comment 1 "Lightning (Wiwynn / Facebook NVMe JBOF) / footprints 294-299 of 495")
	)
	(layers
		(0 "F.Cu" signal "TOP")
		(4 "In1.Cu" signal "L2GND")
		(6 "In2.Cu" signal "L3VCC")
		(2 "B.Cu" signal "BOTTOM")
		(9 "F.Adhes" user "F.Adhesive")
		(11 "B.Adhes" user "B.Adhesive")
		(13 "F.Paste" user "Package Geometry/Pastemask Top")
		(15 "B.Paste" user "Package Geometry/Pastemask Bottom")
		(5 "F.SilkS" user "Ref Des/Silkscreen Top")
		(7 "B.SilkS" user "Ref Des/Silkscreen Bottom")
		(1 "F.Mask" user "Board Geometry/Soldermask Top")
		(3 "B.Mask" user "Board Geometry/Soldermask Bottom")
		(17 "Dwgs.User" user "User.Drawings")
		(19 "Cmts.User" user "User.Comments")
		(21 "Eco1.User" user "User.Eco1")
		(23 "Eco2.User" user "User.Eco2")
		(25 "Edge.Cuts" user "Board Geometry/Outline")
		(27 "Margin" user)
		(31 "F.CrtYd" user "Package Geometry/Place Bound Top")
		(29 "B.CrtYd" user "Package Geometry/Place Bound Bottom")
		(35 "F.Fab" user "Ref Des/Assembly Top")
		(33 "B.Fab" user "Ref Des/Assembly Bottom")
	)
	(footprint ""
		(layer "F.Cu")
		(at 14.3764 -49.0982)
		(property "Reference" "R186"
			(at 0 0 0)
			(layer "F.SilkS")
			(hide yes)
			(effects
				(font
					(size 1.27 1.27)
				)
			)
		)
		(property "Value" "0R2J-2-GP"
			(at 0.064008 -3.993896 0)
			(unlocked yes)
			(layer "F.Fab")
			(hide yes)
			(effects
				(font
					(size 1.016 1.016)
					(thickness 0.1524)
				)
			)
		)
		(property "Device Type" "R402H16"
			(at 0.064008 -5.517896 0)
			(unlocked yes)
			(layer "F.Fab")
			(hide yes)
			(effects
				(font
					(size 1.016 1.016)
					(thickness 0.1524)
				)
			)
		)
		(duplicate_pad_numbers_are_jumpers no)
		(fp_line
			(start -0.508 -0.9398)
			(end -0.508 0.9398)
			(stroke
				(width 0.1524)
				(type default)
			)
			(layer "F.SilkS")
		)
		(fp_line
			(start 0.508 -0.9398)
			(end -0.508 -0.9398)
			(stroke
				(width 0.1524)
				(type default)
			)
			(layer "F.SilkS")
		)
		(fp_rect
			(start -0.508 0.9398)
			(end 0.508 -0.9398)
			(stroke
				(width 0)
				(type default)
			)
			(fill no)
			(layer "F.CrtYd")
		)
		(fp_rect
			(start -0.508 0.9398)
			(end 0.508 -0.9398)
			(stroke
				(width 0)
				(type default)
			)
			(fill no)
			(layer "F.Fab")
		)
		(pad "1" smd custom
			(at 0 -0.4445)
			(size 0.1397 0.1397)
			(layers "F.Cu" "F.Mask" "F.Paste")
			(net "SD_LATCH_RELEASE_U")
			(options
				(clearance outline)
				(anchor circle)
			)
			(primitives
				(gr_poly
					(pts
						(arc
							(start -0.1778 -0.2794)
							(mid -0.249642 -0.249642)
							(end -0.2794 -0.1778)
						)
						(arc
							(start -0.2794 0.1778)
							(mid -0.249642 0.249642)
							(end -0.1778 0.2794)
						)
						(arc
							(start 0.1778 0.2794)
							(mid 0.249642 0.249642)
							(end 0.2794 0.1778)
						)
						(arc
							(start 0.2794 -0.1778)
							(mid 0.249642 -0.249642)
							(end 0.1778 -0.2794)
						)
					)
					(width 0)
					(fill yes)
				)
			)
		)
		(pad "2" smd custom
			(at 0 0.4445)
			(size 0.1397 0.1397)
			(layers "F.Cu" "F.Mask" "F.Paste")
			(net "D_LATCH_PRE#")
			(options
				(clearance outline)
				(anchor circle)
			)
			(primitives
				(gr_poly
					(pts
						(arc
							(start -0.1778 -0.2794)
							(mid -0.249642 -0.249642)
							(end -0.2794 -0.1778)
						)
						(arc
							(start -0.2794 0.1778)
							(mid -0.249642 0.249642)
							(end -0.1778 0.2794)
						)
						(arc
							(start 0.1778 0.2794)
							(mid 0.249642 0.249642)
							(end 0.2794 0.1778)
						)
						(arc
							(start 0.2794 -0.1778)
							(mid 0.249642 -0.249642)
							(end 0.1778 -0.2794)
						)
					)
					(width 0)
					(fill yes)
				)
			)
		)
	)
	(footprint ""
		(layer "F.Cu")
		(at 28.582366 -242.327176)
		(property "Reference" "R42"
			(at 0 0 0)
			(layer "F.SilkS")
			(hide yes)
			(effects
				(font
					(size 1.27 1.27)
				)
			)
		)
		(property "Value" "4K7R2J-2-GP"
			(at 0.064008 -3.993896 0)
			(unlocked yes)
			(layer "F.Fab")
			(hide yes)
			(effects
				(font
					(size 1.016 1.016)
					(thickness 0.1524)
				)
			)
		)
		(property "Device Type" "R402H16"
			(at 0.064008 -5.517896 0)
			(unlocked yes)
			(layer "F.Fab")
			(hide yes)
			(effects
				(font
					(size 1.016 1.016)
					(thickness 0.1524)
				)
			)
		)
		(duplicate_pad_numbers_are_jumpers no)
		(fp_line
			(start -0.508 -0.9398)
			(end -0.508 0.9398)
			(stroke
				(width 0.1524)
				(type default)
			)
			(layer "F.SilkS")
		)
		(fp_line
			(start 0.508 -0.9398)
			(end -0.508 -0.9398)
			(stroke
				(width 0.1524)
				(type default)
			)
			(layer "F.SilkS")
		)
		(fp_rect
			(start -0.508 0.9398)
			(end 0.508 -0.9398)
			(stroke
				(width 0)
				(type default)
			)
			(fill no)
			(layer "F.CrtYd")
		)
		(fp_rect
			(start -0.508 0.9398)
			(end 0.508 -0.9398)
			(stroke
				(width 0)
				(type default)
			)
			(fill no)
			(layer "F.Fab")
		)
		(pad "1" smd custom
			(at 0 -0.4445)
			(size 0.1397 0.1397)
			(layers "F.Cu" "F.Mask" "F.Paste")
			(net "FCB_EEPROM_A0")
			(options
				(clearance outline)
				(anchor circle)
			)
			(primitives
				(gr_poly
					(pts
						(arc
							(start -0.1778 -0.2794)
							(mid -0.249642 -0.249642)
							(end -0.2794 -0.1778)
						)
						(arc
							(start -0.2794 0.1778)
							(mid -0.249642 0.249642)
							(end -0.1778 0.2794)
						)
						(arc
							(start 0.1778 0.2794)
							(mid 0.249642 0.249642)
							(end 0.2794 0.1778)
						)
						(arc
							(start 0.2794 -0.1778)
							(mid 0.249642 -0.249642)
							(end 0.1778 -0.2794)
						)
					)
					(width 0)
					(fill yes)
				)
			)
		)
		(pad "2" smd custom
			(at 0 0.4445)
			(size 0.1397 0.1397)
			(layers "F.Cu" "F.Mask" "F.Paste")
			(net "GND")
			(options
				(clearance outline)
				(anchor circle)
			)
			(primitives
				(gr_poly
					(pts
						(arc
							(start -0.1778 -0.2794)
							(mid -0.249642 -0.249642)
							(end -0.2794 -0.1778)
						)
						(arc
							(start -0.2794 0.1778)
							(mid -0.249642 0.249642)
							(end -0.1778 0.2794)
						)
						(arc
							(start 0.1778 0.2794)
							(mid 0.249642 0.249642)
							(end 0.2794 0.1778)
						)
						(arc
							(start 0.2794 -0.1778)
							(mid 0.249642 -0.249642)
							(end 0.1778 -0.2794)
						)
					)
					(width 0)
					(fill yes)
				)
			)
		)
	)
	(footprint ""
		(layer "F.Cu")
		(at 32.424624 -175.80991 90)
		(property "Reference" "R19"
			(at 0 0 90)
			(layer "F.SilkS")
			(hide yes)
			(effects
				(font
					(size 1.27 1.27)
				)
			)
		)
		(property "Value" "100KR2F-L1-GP"
			(at 0.064008 -3.993896 90)
			(unlocked yes)
			(layer "F.Fab")
			(hide yes)
			(effects
				(font
					(size 1.016 1.016)
					(thickness 0.1524)
				)
			)
		)
		(property "Device Type" "R402H16"
			(at 0.064008 -5.517896 90)
			(unlocked yes)
			(layer "F.Fab")
			(hide yes)
			(effects
				(font
					(size 1.016 1.016)
					(thickness 0.1524)
				)
			)
		)
		(duplicate_pad_numbers_are_jumpers no)
		(fp_line
			(start 0.508 -0.9398)
			(end -0.508 -0.9398)
			(stroke
				(width 0.1524)
				(type default)
			)
			(layer "F.SilkS")
		)
		(fp_line
			(start -0.508 -0.9398)
			(end -0.508 0.9398)
			(stroke
				(width 0.1524)
				(type default)
			)
			(layer "F.SilkS")
		)
		(fp_rect
			(start -0.508 0.9398)
			(end 0.508 -0.9398)
			(stroke
				(width 0)
				(type default)
			)
			(fill no)
			(layer "F.CrtYd")
		)
		(fp_rect
			(start -0.508 0.9398)
			(end 0.508 -0.9398)
			(stroke
				(width 0)
				(type default)
			)
			(fill no)
			(layer "F.Fab")
		)
		(pad "1" smd custom
			(at 0 -0.4445 90)
			(size 0.1397 0.1397)
			(layers "F.Cu" "F.Mask" "F.Paste")
			(net "PWM_EXP_2A")
			(options
				(clearance outline)
				(anchor circle)
			)
			(primitives
				(gr_poly
					(pts
						(arc
							(start -0.1778 -0.2794)
							(mid -0.249642 -0.249642)
							(end -0.2794 -0.1778)
						)
						(arc
							(start -0.2794 0.1778)
							(mid -0.249642 0.249642)
							(end -0.1778 0.2794)
						)
						(arc
							(start 0.1778 0.2794)
							(mid 0.249642 0.249642)
							(end 0.2794 0.1778)
						)
						(arc
							(start 0.2794 -0.1778)
							(mid 0.249642 -0.249642)
							(end 0.1778 -0.2794)
						)
					)
					(width 0)
					(fill yes)
				)
			)
		)
		(pad "2" smd custom
			(at 0 0.4445 90)
			(size 0.1397 0.1397)
			(layers "F.Cu" "F.Mask" "F.Paste")
			(net "GND")
			(options
				(clearance outline)
				(anchor circle)
			)
			(primitives
				(gr_poly
					(pts
						(arc
							(start -0.1778 -0.2794)
							(mid -0.249642 -0.249642)
							(end -0.2794 -0.1778)
						)
						(arc
							(start -0.2794 0.1778)
							(mid -0.249642 0.249642)
							(end -0.1778 0.2794)
						)
						(arc
							(start 0.1778 0.2794)
							(mid 0.249642 0.249642)
							(end 0.2794 0.1778)
						)
						(arc
							(start 0.2794 -0.1778)
							(mid 0.249642 -0.249642)
							(end 0.1778 -0.2794)
						)
					)
					(width 0)
					(fill yes)
				)
			)
		)
	)
	(footprint ""
		(layer "F.Cu")
		(at 14.8844 -42.4942 -90)
		(property "Reference" "R173"
			(at 0 0 270)
			(layer "F.SilkS")
			(hide yes)
			(effects
				(font
					(size 1.27 1.27)
				)
			)
		)
		(property "Value" "0R2J-2-GP"
			(at 0.064008 -3.993896 270)
			(unlocked yes)
			(layer "F.Fab")
			(hide yes)
			(effects
				(font
					(size 1.016 1.016)
					(thickness 0.1524)
				)
			)
		)
		(property "Device Type" "R402H16"
			(at 0.064008 -5.517896 270)
			(unlocked yes)
			(layer "F.Fab")
			(hide yes)
			(effects
				(font
					(size 1.016 1.016)
					(thickness 0.1524)
				)
			)
		)
		(duplicate_pad_numbers_are_jumpers no)
		(fp_line
			(start -0.508 -0.9398)
			(end -0.508 0.9398)
			(stroke
				(width 0.1524)
				(type default)
			)
			(layer "F.SilkS")
		)
		(fp_line
			(start 0.508 -0.9398)
			(end -0.508 -0.9398)
			(stroke
				(width 0.1524)
				(type default)
			)
			(layer "F.SilkS")
		)
		(fp_rect
			(start -0.508 0.9398)
			(end 0.508 -0.9398)
			(stroke
				(width 0)
				(type default)
			)
			(fill no)
			(layer "F.CrtYd")
		)
		(fp_rect
			(start -0.508 0.9398)
			(end 0.508 -0.9398)
			(stroke
				(width 0)
				(type default)
			)
			(fill no)
			(layer "F.Fab")
		)
		(pad "1" smd custom
			(at 0 -0.4445 270)
			(size 0.1397 0.1397)
			(layers "F.Cu" "F.Mask" "F.Paste")
			(net "SELF_2B_HB")
			(options
				(clearance outline)
				(anchor circle)
			)
			(primitives
				(gr_poly
					(pts
						(arc
							(start -0.1778 -0.2794)
							(mid -0.249642 -0.249642)
							(end -0.2794 -0.1778)
						)
						(arc
							(start -0.2794 0.1778)
							(mid -0.249642 0.249642)
							(end -0.1778 0.2794)
						)
						(arc
							(start 0.1778 0.2794)
							(mid 0.249642 0.249642)
							(end 0.2794 0.1778)
						)
						(arc
							(start 0.2794 -0.1778)
							(mid 0.249642 -0.249642)
							(end 0.1778 -0.2794)
						)
					)
					(width 0)
					(fill yes)
				)
			)
		)
		(pad "2" smd custom
			(at 0 0.4445 270)
			(size 0.1397 0.1397)
			(layers "F.Cu" "F.Mask" "F.Paste")
			(net "SEB_PEER_1B_HB")
			(options
				(clearance outline)
				(anchor circle)
			)
			(primitives
				(gr_poly
					(pts
						(arc
							(start -0.1778 -0.2794)
							(mid -0.249642 -0.249642)
							(end -0.2794 -0.1778)
						)
						(arc
							(start -0.2794 0.1778)
							(mid -0.249642 0.249642)
							(end -0.1778 0.2794)
						)
						(arc
							(start 0.1778 0.2794)
							(mid 0.249642 0.249642)
							(end 0.2794 0.1778)
						)
						(arc
							(start 0.2794 -0.1778)
							(mid 0.249642 -0.249642)
							(end 0.1778 -0.2794)
						)
					)
					(width 0)
					(fill yes)
				)
			)
		)
	)
	(footprint ""
		(layer "F.Cu")
		(at 7.949946 -411.465014 -90)
		(property "Reference" "LED2"
			(at 0 0 270)
			(layer "F.SilkS")
			(hide yes)
			(effects
				(font
					(size 1.27 1.27)
				)
			)
		)
		(property "Value" "LED-RB-6-GP"
			(at -4.6736 3.8354 270)
			(unlocked yes)
			(layer "F.Fab")
			(hide yes)
			(effects
				(font
					(size 1.016 1.016)
					(thickness 0.1524)
				)
			)
		)
		(property "Device Type" "LED-100-3P-067106H325"
			(at -4.6736 2.3114 270)
			(unlocked yes)
			(layer "F.Fab")
			(hide yes)
			(effects
				(font
					(size 1.016 1.016)
					(thickness 0.1524)
				)
			)
		)
		(duplicate_pad_numbers_are_jumpers no)
		(fp_line
			(start -1.7526 10.414)
			(end -1.7526 6.6548)
			(stroke
				(width 0.1524)
				(type default)
			)
			(layer "F.SilkS")
		)
		(fp_line
			(start 1.7526 10.414)
			(end -1.7526 10.414)
			(stroke
				(width 0.1524)
				(type default)
			)
			(layer "F.SilkS")
		)
		(fp_line
			(start -3.6068 6.6548)
			(end -3.6068 -0.889)
			(stroke
				(width 0.1524)
				(type default)
			)
			(layer "F.SilkS")
		)
		(fp_line
			(start -1.7526 6.6548)
			(end -3.6068 6.6548)
			(stroke
				(width 0.1524)
				(type default)
			)
			(layer "F.SilkS")
		)
		(fp_line
			(start 1.7526 6.6548)
			(end 1.7526 10.414)
			(stroke
				(width 0.1524)
				(type default)
			)
			(layer "F.SilkS")
		)
		(fp_line
			(start 3.6068 6.6548)
			(end 1.7526 6.6548)
			(stroke
				(width 0.1524)
				(type default)
			)
			(layer "F.SilkS")
		)
		(fp_line
			(start -3.6068 -0.889)
			(end 3.6068 -0.889)
			(stroke
				(width 0.1524)
				(type default)
			)
			(layer "F.SilkS")
		)
		(fp_line
			(start 3.6068 -0.889)
			(end 3.6068 6.6548)
			(stroke
				(width 0.1524)
				(type default)
			)
			(layer "F.SilkS")
		)
		(fp_circle
			(center -2.54 0)
			(end -2.54 -0.9906)
			(stroke
				(width 0.3048)
				(type default)
			)
			(fill no)
			(layer "F.SilkS")
		)
		(fp_circle
			(center 0 0)
			(end 0 -0.9906)
			(stroke
				(width 0.3048)
				(type default)
			)
			(fill no)
			(layer "F.SilkS")
		)
		(fp_circle
			(center 2.54 0)
			(end 2.54 -0.9906)
			(stroke
				(width 0.3048)
				(type default)
			)
			(fill no)
			(layer "F.SilkS")
		)
		(fp_poly
			(pts
				(xy -1.4986 10.1473) (xy -1.4986 6.4008) (xy -3.3528 6.4008) (xy -3.3528 -0.3937) (xy 3.3528 -0.3937)
				(xy 3.3528 6.4008) (xy 1.4986 6.4008) (xy 1.4986 10.1473)
			)
			(stroke
				(width 0)
				(type default)
			)
			(fill no)
			(layer "F.CrtYd")
		)
		(fp_poly
			(pts
				(xy -2.0066 10.668) (xy 2.0066 10.668) (xy 2.0066 6.9088) (xy 3.8608 6.9088) (xy 3.8608 2.2098)
				(xy 3.3528 2.2098) (xy 3.3528 6.4008) (xy 1.4986 6.4008) (xy 1.4986 10.1473) (xy -1.4986 10.1473)
				(xy -1.4986 6.4008) (xy -3.3528 6.4008) (xy -3.3528 -0.3937) (xy 3.3528 -0.3937) (xy 3.3528 2.1971)
				(xy 3.8608 2.1971) (xy 3.8608 -1.143) (xy -3.8608 -1.143) (xy -3.8608 6.9088) (xy -2.0066 6.9088)
			)
			(stroke
				(width 0)
				(type default)
			)
			(fill no)
			(layer "F.CrtYd")
		)
		(fp_poly
			(pts
				(xy -2.0066 10.668) (xy -2.0066 6.9088) (xy -3.8608 6.9088) (xy -3.8608 -1.143) (xy 3.8608 -1.143)
				(xy 3.8608 6.9088) (xy 2.0066 6.9088) (xy 2.0066 10.668)
			)
			(stroke
				(width 0)
				(type default)
			)
			(fill no)
			(layer "F.Fab")
		)
		(pad "1" thru_hole circle
			(at 2.54 0 270)
			(size 1.27 1.27)
			(drill 0.889)
			(layers "*.Cu" "*.Mask")
			(remove_unused_layers no)
			(net "LED_DR_LED1_BLUE")
			(clearance 0.1651)
			(thermal_gap 0.1651)
		)
		(pad "2" thru_hole circle
			(at 0 0 270)
			(size 1.27 1.27)
			(drill 0.889)
			(layers "*.Cu" "*.Mask")
			(remove_unused_layers no)
			(net "LED_DR_LED1_K")
			(clearance 0.1651)
			(thermal_gap 0.1651)
		)
		(pad "3" thru_hole circle
			(at -2.54 0 270)
			(size 1.27 1.27)
			(drill 0.889)
			(layers "*.Cu" "*.Mask")
			(remove_unused_layers no)
			(net "LED_DR_LED1")
			(clearance 0.1651)
			(thermal_gap 0.1651)
		)
	)
	(footprint ""
		(layer "F.Cu")
		(at 28.8544 -357.6828 90)
		(property "Reference" "R366"
			(at 0 0 90)
			(layer "F.SilkS")
			(hide yes)
			(effects
				(font
					(size 1.27 1.27)
				)
			)
		)
		(property "Value" "10KR2F-2-GP"
			(at 0.064008 -3.993896 90)
			(unlocked yes)
			(layer "F.Fab")
			(hide yes)
			(effects
				(font
					(size 1.016 1.016)
					(thickness 0.1524)
				)
			)
		)
		(property "Device Type" "R402H16"
			(at 0.064008 -5.517896 90)
			(unlocked yes)
			(layer "F.Fab")
			(hide yes)
			(effects
				(font
					(size 1.016 1.016)
					(thickness 0.1524)
				)
			)
		)
		(duplicate_pad_numbers_are_jumpers no)
		(fp_line
			(start 0.508 -0.9398)
			(end -0.508 -0.9398)
			(stroke
				(width 0.1524)
				(type default)
			)
			(layer "F.SilkS")
		)
		(fp_line
			(start -0.508 -0.9398)
			(end -0.508 0.9398)
			(stroke
				(width 0.1524)
				(type default)
			)
			(layer "F.SilkS")
		)
		(fp_rect
			(start -0.508 0.9398)
			(end 0.508 -0.9398)
			(stroke
				(width 0)
				(type default)
			)
			(fill no)
			(layer "F.CrtYd")
		)
		(fp_rect
			(start -0.508 0.9398)
			(end 0.508 -0.9398)
			(stroke
				(width 0)
				(type default)
			)
			(fill no)
			(layer "F.Fab")
		)
		(pad "1" smd custom
			(at 0 -0.4445 90)
			(size 0.1397 0.1397)
			(layers "F.Cu" "F.Mask" "F.Paste")
			(net "P3V3")
			(options
				(clearance outline)
				(anchor circle)
			)
			(primitives
				(gr_poly
					(pts
						(arc
							(start -0.1778 -0.2794)
							(mid -0.249642 -0.249642)
							(end -0.2794 -0.1778)
						)
						(arc
							(start -0.2794 0.1778)
							(mid -0.249642 0.249642)
							(end -0.1778 0.2794)
						)
						(arc
							(start 0.1778 0.2794)
							(mid 0.249642 0.249642)
							(end 0.2794 0.1778)
						)
						(arc
							(start 0.2794 -0.1778)
							(mid 0.249642 -0.249642)
							(end 0.1778 -0.2794)
						)
					)
					(width 0)
					(fill yes)
				)
			)
		)
		(pad "2" smd custom
			(at 0 0.4445 90)
			(size 0.1397 0.1397)
			(layers "F.Cu" "F.Mask" "F.Paste")
			(net "TEMP_ALM#")
			(options
				(clearance outline)
				(anchor circle)
			)
			(primitives
				(gr_poly
					(pts
						(arc
							(start -0.1778 -0.2794)
							(mid -0.249642 -0.249642)
							(end -0.2794 -0.1778)
						)
						(arc
							(start -0.2794 0.1778)
							(mid -0.249642 0.249642)
							(end -0.1778 0.2794)
						)
						(arc
							(start 0.1778 0.2794)
							(mid 0.249642 0.249642)
							(end 0.2794 0.1778)
						)
						(arc
							(start 0.2794 -0.1778)
							(mid 0.249642 -0.249642)
							(end 0.1778 -0.2794)
						)
					)
					(width 0)
					(fill yes)
				)
			)
		)
	)
)
